(kicad_pcb
	(version 20260206)
	(generator "pcbnew")
	(generator_version "10.0")
	(general
		(thickness 1.6)
		(legacy_teardrops no)
	)
	(paper "A4")
	(title_block
		(title "03242023_DA0F0TMBIJ0_F0T_Motherboard_J_brd_V01_OCP.brd")
		(comment 1 "Grand Teton / footprints 886-892 of 6105")
	)
	(layers
		(0 "F.Cu" signal "TOP")
		(4 "In1.Cu" signal "GND")
		(6 "In2.Cu" signal "IN1")
		(8 "In3.Cu" signal "GND1")
		(10 "In4.Cu" signal "IN2")
		(12 "In5.Cu" signal "GND2")
		(14 "In6.Cu" signal "IN3")
		(16 "In7.Cu" signal "GND3")
		(18 "In8.Cu" signal "VCC")
		(20 "In9.Cu" signal "VCC1")
		(22 "In10.Cu" signal "GND4")
		(24 "In11.Cu" signal "IN4")
		(26 "In12.Cu" signal "GND5")
		(28 "In13.Cu" signal "IN5")
		(30 "In14.Cu" signal "GND6")
		(32 "In15.Cu" signal "IN6")
		(34 "In16.Cu" signal "GND7")
		(2 "B.Cu" signal "BOTTOM")
		(9 "F.Adhes" user "F.Adhesive")
		(11 "B.Adhes" user "B.Adhesive")
		(13 "F.Paste" user "Package Geometry/Pastemask Top")
		(15 "B.Paste" user "Package Geometry/Pastemask Bottom")
		(5 "F.SilkS" user "Ref Des/Silkscreen Top")
		(7 "B.SilkS" user "Ref Des/Silkscreen Bottom")
		(1 "F.Mask" user "Board Geometry/Soldermask Top")
		(3 "B.Mask" user "Board Geometry/Soldermask Bottom")
		(17 "Dwgs.User" user "User.Drawings")
		(19 "Cmts.User" user "User.Comments")
		(21 "Eco1.User" user "User.Eco1")
		(23 "Eco2.User" user "User.Eco2")
		(25 "Edge.Cuts" user "Board Geometry/Outline")
		(27 "Margin" user)
		(31 "F.CrtYd" user "Package Geometry/Place Bound Top")
		(29 "B.CrtYd" user "Package Geometry/Place Bound Bottom")
		(35 "F.Fab" user "Ref Des/Assembly Top")
		(33 "B.Fab" user "Ref Des/Assembly Bottom")
	)
	(footprint ""
		(layer "F.Cu")
		(at 332.438248 -402.371052 -90)
		(property "Reference" "C1793"
			(at 0 0 270)
			(layer "F.SilkS")
			(hide yes)
			(effects
				(font
					(size 1.27 1.27)
				)
			)
		)
		(property "Value" ""
			(at 0 0 270)
			(layer "F.Fab")
			(effects
				(font
					(size 1.27 1.27)
				)
			)
		)
		(duplicate_pad_numbers_are_jumpers no)
		(fp_line
			(start -0.299974 0.150114)
			(end -0.299974 -0.150114)
			(stroke
				(width 0.1)
				(type default)
			)
			(layer "F.Fab")
		)
		(fp_line
			(start 0.299974 0.150114)
			(end -0.299974 0.150114)
			(stroke
				(width 0.1)
				(type default)
			)
			(layer "F.Fab")
		)
		(fp_line
			(start -0.299974 -0.150114)
			(end 0.299974 -0.150114)
			(stroke
				(width 0.1)
				(type default)
			)
			(layer "F.Fab")
		)
		(fp_line
			(start 0.299974 -0.150114)
			(end 0.299974 0.150114)
			(stroke
				(width 0.1)
				(type default)
			)
			(layer "F.Fab")
		)
		(pad "1" smd rect
			(at -0.2667 0 270)
			(size 0.3048 0.381)
			(layers "F.Cu" "F.Mask" "F.Paste")
			(net "P5E_CPU0_PE4_TX_C_DP<9>")
		)
		(pad "2" smd rect
			(at 0.2667 0 270)
			(size 0.3048 0.381)
			(layers "F.Cu" "F.Mask" "F.Paste")
			(net "P5E_CPU0_PE4_TX_DP<9>")
		)
	)
	(footprint ""
		(layer "F.Cu")
		(at 217.881962 -67.324478 180)
		(property "Reference" "PR3965"
			(at 0 0 180)
			(layer "F.SilkS")
			(hide yes)
			(effects
				(font
					(size 1.27 1.27)
				)
			)
		)
		(property "Value" ""
			(at 0 0 180)
			(layer "F.Fab")
			(effects
				(font
					(size 1.27 1.27)
				)
			)
		)
		(duplicate_pad_numbers_are_jumpers no)
		(fp_line
			(start 0.7874 0.4064)
			(end -0.7874 0.4064)
			(stroke
				(width 0.1524)
				(type default)
			)
			(layer "F.SilkS")
		)
		(fp_line
			(start 0.7874 -0.4064)
			(end 0.7874 0.4064)
			(stroke
				(width 0.1524)
				(type default)
			)
			(layer "F.SilkS")
		)
		(fp_line
			(start -0.7874 0.4064)
			(end -0.7874 -0.4064)
			(stroke
				(width 0.1524)
				(type default)
			)
			(layer "F.SilkS")
		)
		(fp_line
			(start -0.7874 -0.4064)
			(end 0.7874 -0.4064)
			(stroke
				(width 0.1524)
				(type default)
			)
			(layer "F.SilkS")
		)
		(fp_line
			(start 0.67945 0.3048)
			(end 0.120396 0.3048)
			(stroke
				(width 0.1)
				(type default)
			)
			(layer "F.Fab")
		)
		(fp_line
			(start 0.67945 -0.3048)
			(end 0.67945 0.3048)
			(stroke
				(width 0.1)
				(type default)
			)
			(layer "F.Fab")
		)
		(fp_line
			(start 0.12065 -0.2794)
			(end 0.12065 -0.3048)
			(stroke
				(width 0.1)
				(type default)
			)
			(layer "F.Fab")
		)
		(fp_line
			(start 0.12065 -0.3048)
			(end 0.67945 -0.3048)
			(stroke
				(width 0.1)
				(type default)
			)
			(layer "F.Fab")
		)
		(fp_line
			(start 0.120396 0.3048)
			(end 0.120396 0.2794)
			(stroke
				(width 0.1)
				(type default)
			)
			(layer "F.Fab")
		)
		(fp_line
			(start 0.120396 0.2794)
			(end -0.12065 0.2794)
			(stroke
				(width 0.1)
				(type default)
			)
			(layer "F.Fab")
		)
		(fp_line
			(start -0.12065 0.3048)
			(end -0.67945 0.3048)
			(stroke
				(width 0.1)
				(type default)
			)
			(layer "F.Fab")
		)
		(fp_line
			(start -0.12065 0.2794)
			(end -0.12065 0.3048)
			(stroke
				(width 0.1)
				(type default)
			)
			(layer "F.Fab")
		)
		(fp_line
			(start -0.12065 -0.2794)
			(end 0.12065 -0.2794)
			(stroke
				(width 0.1)
				(type default)
			)
			(layer "F.Fab")
		)
		(fp_line
			(start -0.12065 -0.305054)
			(end -0.12065 -0.2794)
			(stroke
				(width 0.1)
				(type default)
			)
			(layer "F.Fab")
		)
		(fp_line
			(start -0.67945 0.3048)
			(end -0.67945 -0.305054)
			(stroke
				(width 0.1)
				(type default)
			)
			(layer "F.Fab")
		)
		(fp_line
			(start -0.67945 -0.305054)
			(end -0.12065 -0.305054)
			(stroke
				(width 0.1)
				(type default)
			)
			(layer "F.Fab")
		)
		(pad "1" smd circle
			(at -0.40005 0 180)
			(size 0 0)
			(layers "F.Cu" "F.Mask" "F.Paste")
			(net "P3V3_E1S_OV_0")
		)
		(pad "2" smd circle
			(at 0.40005 0 180)
			(size 0 0)
			(layers "F.Cu" "F.Mask" "F.Paste")
			(net "GND")
		)
	)
	(footprint ""
		(layer "F.Cu")
		(at 211.455 -68.253356 -90)
		(property "Reference" "R4710"
			(at 0 0 270)
			(layer "F.SilkS")
			(hide yes)
			(effects
				(font
					(size 1.27 1.27)
				)
			)
		)
		(property "Value" ""
			(at 0 0 270)
			(layer "F.Fab")
			(effects
				(font
					(size 1.27 1.27)
				)
			)
		)
		(duplicate_pad_numbers_are_jumpers no)
		(fp_line
			(start -0.7874 0.4064)
			(end -0.7874 -0.4064)
			(stroke
				(width 0.1524)
				(type default)
			)
			(layer "F.SilkS")
		)
		(fp_line
			(start 0.7874 0.4064)
			(end -0.7874 0.4064)
			(stroke
				(width 0.1524)
				(type default)
			)
			(layer "F.SilkS")
		)
		(fp_line
			(start -0.7874 -0.4064)
			(end 0.7874 -0.4064)
			(stroke
				(width 0.1524)
				(type default)
			)
			(layer "F.SilkS")
		)
		(fp_line
			(start 0.7874 -0.4064)
			(end 0.7874 0.4064)
			(stroke
				(width 0.1524)
				(type default)
			)
			(layer "F.SilkS")
		)
		(fp_line
			(start -0.67945 0.3048)
			(end -0.67945 -0.305054)
			(stroke
				(width 0.1)
				(type default)
			)
			(layer "F.Fab")
		)
		(fp_line
			(start -0.12065 0.3048)
			(end -0.67945 0.3048)
			(stroke
				(width 0.1)
				(type default)
			)
			(layer "F.Fab")
		)
		(fp_line
			(start 0.120396 0.3048)
			(end 0.120396 0.2794)
			(stroke
				(width 0.1)
				(type default)
			)
			(layer "F.Fab")
		)
		(fp_line
			(start 0.67945 0.3048)
			(end 0.120396 0.3048)
			(stroke
				(width 0.1)
				(type default)
			)
			(layer "F.Fab")
		)
		(fp_line
			(start -0.12065 0.2794)
			(end -0.12065 0.3048)
			(stroke
				(width 0.1)
				(type default)
			)
			(layer "F.Fab")
		)
		(fp_line
			(start 0.120396 0.2794)
			(end -0.12065 0.2794)
			(stroke
				(width 0.1)
				(type default)
			)
			(layer "F.Fab")
		)
		(fp_line
			(start -0.12065 -0.2794)
			(end 0.12065 -0.2794)
			(stroke
				(width 0.1)
				(type default)
			)
			(layer "F.Fab")
		)
		(fp_line
			(start 0.12065 -0.2794)
			(end 0.12065 -0.3048)
			(stroke
				(width 0.1)
				(type default)
			)
			(layer "F.Fab")
		)
		(fp_line
			(start 0.12065 -0.3048)
			(end 0.67945 -0.3048)
			(stroke
				(width 0.1)
				(type default)
			)
			(layer "F.Fab")
		)
		(fp_line
			(start 0.67945 -0.3048)
			(end 0.67945 0.3048)
			(stroke
				(width 0.1)
				(type default)
			)
			(layer "F.Fab")
		)
		(fp_line
			(start -0.67945 -0.305054)
			(end -0.12065 -0.305054)
			(stroke
				(width 0.1)
				(type default)
			)
			(layer "F.Fab")
		)
		(fp_line
			(start -0.12065 -0.305054)
			(end -0.12065 -0.2794)
			(stroke
				(width 0.1)
				(type default)
			)
			(layer "F.Fab")
		)
		(pad "1" smd circle
			(at -0.40005 0 270)
			(size 0 0)
			(layers "F.Cu" "F.Mask" "F.Paste")
			(net "P3V3_AUX")
		)
		(pad "2" smd circle
			(at 0.40005 0 270)
			(size 0 0)
			(layers "F.Cu" "F.Mask" "F.Paste")
			(net "LED_P12V_SCM_FAULT_D1")
		)
	)
	(footprint ""
		(layer "F.Cu")
		(at 385.637532 -73.394824 180)
		(property "Reference" "R2359"
			(at 0 0 180)
			(layer "F.SilkS")
			(hide yes)
			(effects
				(font
					(size 1.27 1.27)
				)
			)
		)
		(property "Value" ""
			(at 0 0 180)
			(layer "F.Fab")
			(effects
				(font
					(size 1.27 1.27)
				)
			)
		)
		(duplicate_pad_numbers_are_jumpers no)
		(fp_line
			(start 0.7874 0.4064)
			(end -0.7874 0.4064)
			(stroke
				(width 0.1524)
				(type default)
			)
			(layer "F.SilkS")
		)
		(fp_line
			(start 0.7874 -0.4064)
			(end 0.7874 0.4064)
			(stroke
				(width 0.1524)
				(type default)
			)
			(layer "F.SilkS")
		)
		(fp_line
			(start -0.7874 0.4064)
			(end -0.7874 -0.4064)
			(stroke
				(width 0.1524)
				(type default)
			)
			(layer "F.SilkS")
		)
		(fp_line
			(start -0.7874 -0.4064)
			(end 0.7874 -0.4064)
			(stroke
				(width 0.1524)
				(type default)
			)
			(layer "F.SilkS")
		)
		(fp_line
			(start 0.67945 0.3048)
			(end 0.120396 0.3048)
			(stroke
				(width 0.1)
				(type default)
			)
			(layer "F.Fab")
		)
		(fp_line
			(start 0.67945 -0.3048)
			(end 0.67945 0.3048)
			(stroke
				(width 0.1)
				(type default)
			)
			(layer "F.Fab")
		)
		(fp_line
			(start 0.12065 -0.2794)
			(end 0.12065 -0.3048)
			(stroke
				(width 0.1)
				(type default)
			)
			(layer "F.Fab")
		)
		(fp_line
			(start 0.12065 -0.3048)
			(end 0.67945 -0.3048)
			(stroke
				(width 0.1)
				(type default)
			)
			(layer "F.Fab")
		)
		(fp_line
			(start 0.120396 0.3048)
			(end 0.120396 0.2794)
			(stroke
				(width 0.1)
				(type default)
			)
			(layer "F.Fab")
		)
		(fp_line
			(start 0.120396 0.2794)
			(end -0.12065 0.2794)
			(stroke
				(width 0.1)
				(type default)
			)
			(layer "F.Fab")
		)
		(fp_line
			(start -0.12065 0.3048)
			(end -0.67945 0.3048)
			(stroke
				(width 0.1)
				(type default)
			)
			(layer "F.Fab")
		)
		(fp_line
			(start -0.12065 0.2794)
			(end -0.12065 0.3048)
			(stroke
				(width 0.1)
				(type default)
			)
			(layer "F.Fab")
		)
		(fp_line
			(start -0.12065 -0.2794)
			(end 0.12065 -0.2794)
			(stroke
				(width 0.1)
				(type default)
			)
			(layer "F.Fab")
		)
		(fp_line
			(start -0.12065 -0.305054)
			(end -0.12065 -0.2794)
			(stroke
				(width 0.1)
				(type default)
			)
			(layer "F.Fab")
		)
		(fp_line
			(start -0.67945 0.3048)
			(end -0.67945 -0.305054)
			(stroke
				(width 0.1)
				(type default)
			)
			(layer "F.Fab")
		)
		(fp_line
			(start -0.67945 -0.305054)
			(end -0.12065 -0.305054)
			(stroke
				(width 0.1)
				(type default)
			)
			(layer "F.Fab")
		)
		(pad "1" smd circle
			(at -0.40005 0 180)
			(size 0 0)
			(layers "F.Cu" "F.Mask" "F.Paste")
			(net "P3V3_AUX")
		)
		(pad "2" smd circle
			(at 0.40005 0 180)
			(size 0 0)
			(layers "F.Cu" "F.Mask" "F.Paste")
			(net "PWRGD_P1V8_PCH_AUX_R")
		)
	)
	(footprint ""
		(layer "F.Cu")
		(at 372.13159 -68.930012)
		(property "Reference" "C546"
			(at 0 0 0)
			(layer "F.SilkS")
			(hide yes)
			(effects
				(font
					(size 1.27 1.27)
				)
			)
		)
		(property "Value" ""
			(at 0 0 0)
			(layer "F.Fab")
			(effects
				(font
					(size 1.27 1.27)
				)
			)
		)
		(duplicate_pad_numbers_are_jumpers no)
		(fp_line
			(start -0.7874 -0.4064)
			(end 0.7874 -0.4064)
			(stroke
				(width 0.1524)
				(type default)
			)
			(layer "F.SilkS")
		)
		(fp_line
			(start -0.7874 0.4064)
			(end -0.7874 -0.4064)
			(stroke
				(width 0.1524)
				(type default)
			)
			(layer "F.SilkS")
		)
		(fp_line
			(start 0.7874 -0.4064)
			(end 0.7874 0.4064)
			(stroke
				(width 0.1524)
				(type default)
			)
			(layer "F.SilkS")
		)
		(fp_line
			(start 0.7874 0.4064)
			(end -0.7874 0.4064)
			(stroke
				(width 0.1524)
				(type default)
			)
			(layer "F.SilkS")
		)
		(fp_line
			(start -0.67945 -0.305054)
			(end -0.12065 -0.305054)
			(stroke
				(width 0.1)
				(type default)
			)
			(layer "F.Fab")
		)
		(fp_line
			(start -0.67945 0.3048)
			(end -0.67945 -0.305054)
			(stroke
				(width 0.1)
				(type default)
			)
			(layer "F.Fab")
		)
		(fp_line
			(start -0.12065 -0.305054)
			(end -0.12065 -0.2794)
			(stroke
				(width 0.1)
				(type default)
			)
			(layer "F.Fab")
		)
		(fp_line
			(start -0.12065 -0.2794)
			(end 0.12065 -0.2794)
			(stroke
				(width 0.1)
				(type default)
			)
			(layer "F.Fab")
		)
		(fp_line
			(start -0.12065 0.2794)
			(end -0.12065 0.3048)
			(stroke
				(width 0.1)
				(type default)
			)
			(layer "F.Fab")
		)
		(fp_line
			(start -0.12065 0.3048)
			(end -0.67945 0.3048)
			(stroke
				(width 0.1)
				(type default)
			)
			(layer "F.Fab")
		)
		(fp_line
			(start 0.120396 0.2794)
			(end -0.12065 0.2794)
			(stroke
				(width 0.1)
				(type default)
			)
			(layer "F.Fab")
		)
		(fp_line
			(start 0.120396 0.3048)
			(end 0.120396 0.2794)
			(stroke
				(width 0.1)
				(type default)
			)
			(layer "F.Fab")
		)
		(fp_line
			(start 0.12065 -0.3048)
			(end 0.67945 -0.3048)
			(stroke
				(width 0.1)
				(type default)
			)
			(layer "F.Fab")
		)
		(fp_line
			(start 0.12065 -0.2794)
			(end 0.12065 -0.3048)
			(stroke
				(width 0.1)
				(type default)
			)
			(layer "F.Fab")
		)
		(fp_line
			(start 0.67945 -0.3048)
			(end 0.67945 0.3048)
			(stroke
				(width 0.1)
				(type default)
			)
			(layer "F.Fab")
		)
		(fp_line
			(start 0.67945 0.3048)
			(end 0.120396 0.3048)
			(stroke
				(width 0.1)
				(type default)
			)
			(layer "F.Fab")
		)
		(pad "1" smd circle
			(at -0.40005 0)
			(size 0 0)
			(layers "F.Cu" "F.Mask" "F.Paste")
			(net "P3V3_AUX")
		)
		(pad "2" smd circle
			(at 0.40005 0)
			(size 0 0)
			(layers "F.Cu" "F.Mask" "F.Paste")
			(net "GND")
		)
	)
	(footprint ""
		(layer "F.Cu")
		(at 465.043266 -101.39299 180)
		(property "Reference" "R1149"
			(at 0 0 180)
			(layer "F.SilkS")
			(hide yes)
			(effects
				(font
					(size 1.27 1.27)
				)
			)
		)
		(property "Value" ""
			(at 0 0 180)
			(layer "F.Fab")
			(effects
				(font
					(size 1.27 1.27)
				)
			)
		)
		(duplicate_pad_numbers_are_jumpers no)
		(fp_line
			(start 0.7874 0.4064)
			(end -0.7874 0.4064)
			(stroke
				(width 0.1524)
				(type default)
			)
			(layer "F.SilkS")
		)
		(fp_line
			(start 0.7874 -0.4064)
			(end 0.7874 0.4064)
			(stroke
				(width 0.1524)
				(type default)
			)
			(layer "F.SilkS")
		)
		(fp_line
			(start -0.7874 0.4064)
			(end -0.7874 -0.4064)
			(stroke
				(width 0.1524)
				(type default)
			)
			(layer "F.SilkS")
		)
		(fp_line
			(start -0.7874 -0.4064)
			(end 0.7874 -0.4064)
			(stroke
				(width 0.1524)
				(type default)
			)
			(layer "F.SilkS")
		)
		(fp_line
			(start 0.67945 0.3048)
			(end 0.120396 0.3048)
			(stroke
				(width 0.1)
				(type default)
			)
			(layer "F.Fab")
		)
		(fp_line
			(start 0.67945 -0.3048)
			(end 0.67945 0.3048)
			(stroke
				(width 0.1)
				(type default)
			)
			(layer "F.Fab")
		)
		(fp_line
			(start 0.12065 -0.2794)
			(end 0.12065 -0.3048)
			(stroke
				(width 0.1)
				(type default)
			)
			(layer "F.Fab")
		)
		(fp_line
			(start 0.12065 -0.3048)
			(end 0.67945 -0.3048)
			(stroke
				(width 0.1)
				(type default)
			)
			(layer "F.Fab")
		)
		(fp_line
			(start 0.120396 0.3048)
			(end 0.120396 0.2794)
			(stroke
				(width 0.1)
				(type default)
			)
			(layer "F.Fab")
		)
		(fp_line
			(start 0.120396 0.2794)
			(end -0.12065 0.2794)
			(stroke
				(width 0.1)
				(type default)
			)
			(layer "F.Fab")
		)
		(fp_line
			(start -0.12065 0.3048)
			(end -0.67945 0.3048)
			(stroke
				(width 0.1)
				(type default)
			)
			(layer "F.Fab")
		)
		(fp_line
			(start -0.12065 0.2794)
			(end -0.12065 0.3048)
			(stroke
				(width 0.1)
				(type default)
			)
			(layer "F.Fab")
		)
		(fp_line
			(start -0.12065 -0.2794)
			(end 0.12065 -0.2794)
			(stroke
				(width 0.1)
				(type default)
			)
			(layer "F.Fab")
		)
		(fp_line
			(start -0.12065 -0.305054)
			(end -0.12065 -0.2794)
			(stroke
				(width 0.1)
				(type default)
			)
			(layer "F.Fab")
		)
		(fp_line
			(start -0.67945 0.3048)
			(end -0.67945 -0.305054)
			(stroke
				(width 0.1)
				(type default)
			)
			(layer "F.Fab")
		)
		(fp_line
			(start -0.67945 -0.305054)
			(end -0.12065 -0.305054)
			(stroke
				(width 0.1)
				(type default)
			)
			(layer "F.Fab")
		)
		(pad "1" smd circle
			(at -0.40005 0 180)
			(size 0 0)
			(layers "F.Cu" "F.Mask" "F.Paste")
			(net "P3V3_AUX")
		)
		(pad "2" smd circle
			(at 0.40005 0 180)
			(size 0 0)
			(layers "F.Cu" "F.Mask" "F.Paste")
			(net "HP_LVC3_OCP_V3_1_ATTN_OUT_SW_N")
		)
	)
	(footprint ""
		(layer "F.Cu")
		(at 120.37822 -423.479468)
		(property "Reference" "R3508"
			(at 0 0 0)
			(layer "F.SilkS")
			(hide yes)
			(effects
				(font
					(size 1.27 1.27)
				)
			)
		)
		(property "Value" ""
			(at 0 0 0)
			(layer "F.Fab")
			(effects
				(font
					(size 1.27 1.27)
				)
			)
		)
		(duplicate_pad_numbers_are_jumpers no)
		(fp_line
			(start -0.7874 -0.4064)
			(end 0.7874 -0.4064)
			(stroke
				(width 0.1524)
				(type default)
			)
			(layer "F.SilkS")
		)
		(fp_line
			(start -0.7874 0.4064)
			(end -0.7874 -0.4064)
			(stroke
				(width 0.1524)
				(type default)
			)
			(layer "F.SilkS")
		)
		(fp_line
			(start 0.7874 -0.4064)
			(end 0.7874 0.4064)
			(stroke
				(width 0.1524)
				(type default)
			)
			(layer "F.SilkS")
		)
		(fp_line
			(start 0.7874 0.4064)
			(end -0.7874 0.4064)
			(stroke
				(width 0.1524)
				(type default)
			)
			(layer "F.SilkS")
		)
		(fp_line
			(start -0.67945 -0.305054)
			(end -0.12065 -0.305054)
			(stroke
				(width 0.1)
				(type default)
			)
			(layer "F.Fab")
		)
		(fp_line
			(start -0.67945 0.3048)
			(end -0.67945 -0.305054)
			(stroke
				(width 0.1)
				(type default)
			)
			(layer "F.Fab")
		)
		(fp_line
			(start -0.12065 -0.305054)
			(end -0.12065 -0.2794)
			(stroke
				(width 0.1)
				(type default)
			)
			(layer "F.Fab")
		)
		(fp_line
			(start -0.12065 -0.2794)
			(end 0.12065 -0.2794)
			(stroke
				(width 0.1)
				(type default)
			)
			(layer "F.Fab")
		)
		(fp_line
			(start -0.12065 0.2794)
			(end -0.12065 0.3048)
			(stroke
				(width 0.1)
				(type default)
			)
			(layer "F.Fab")
		)
		(fp_line
			(start -0.12065 0.3048)
			(end -0.67945 0.3048)
			(stroke
				(width 0.1)
				(type default)
			)
			(layer "F.Fab")
		)
		(fp_line
			(start 0.120396 0.2794)
			(end -0.12065 0.2794)
			(stroke
				(width 0.1)
				(type default)
			)
			(layer "F.Fab")
		)
		(fp_line
			(start 0.120396 0.3048)
			(end 0.120396 0.2794)
			(stroke
				(width 0.1)
				(type default)
			)
			(layer "F.Fab")
		)
		(fp_line
			(start 0.12065 -0.3048)
			(end 0.67945 -0.3048)
			(stroke
				(width 0.1)
				(type default)
			)
			(layer "F.Fab")
		)
		(fp_line
			(start 0.12065 -0.2794)
			(end 0.12065 -0.3048)
			(stroke
				(width 0.1)
				(type default)
			)
			(layer "F.Fab")
		)
		(fp_line
			(start 0.67945 -0.3048)
			(end 0.67945 0.3048)
			(stroke
				(width 0.1)
				(type default)
			)
			(layer "F.Fab")
		)
		(fp_line
			(start 0.67945 0.3048)
			(end 0.120396 0.3048)
			(stroke
				(width 0.1)
				(type default)
			)
			(layer "F.Fab")
		)
		(pad "1" smd circle
			(at -0.40005 0)
			(size 0 0)
			(layers "F.Cu" "F.Mask" "F.Paste")
			(net "FM_GPU_PWR_EN_R1")
		)
		(pad "2" smd circle
			(at 0.40005 0)
			(size 0 0)
			(layers "F.Cu" "F.Mask" "F.Paste")
			(net "GND")
		)
	)
)
